# BASEBOARD_FAB2 (Tioga Pass) — schematic netlist excerpt (pin names and nets, part order shuffled) for the footprints in the layout excerpt that follows; sources: Cadence DE-HDL packaged netlist, KiCad conversion of Wiwynn_Tioga_Pass_MB.brd

R2U33  RES  20.0 1% CHIP  pkg 0402  page 159 : A = SMB_HOST_STBY_LVC3_SDA_R ; B = SMB_HOST_STBY_LVC3_SDA

Q8E2  FET_N  2N7002 FET  pkg SOT23LF  page 126
  GATE  = RST_RSMRST_DLY
  SRC  = GND
  DRN  = IRQ_SML0_ALERT_N

C8B5  CAP_A  0.1UF 16V 10% X7R  pkg 0402V  page 198 : A = P5V_STBY ; B = GND

(kicad_pcb
	(version 20260206)
	(generator "pcbnew")
	(generator_version "10.0")
	(general
		(thickness 1.6)
		(legacy_teardrops no)
	)
	(paper "A4")
	(title_block
		(title "Wiwynn_Tioga_Pass_MB.brd")
		(comment 1 "Tioga Pass / footprints 1701-1703 of 4770")
	)
	(layers
		(0 "F.Cu" signal "TOP")
		(4 "In1.Cu" signal "L2GND")
		(6 "In2.Cu" signal "L3")
		(8 "In3.Cu" signal "L4GND")
		(10 "In4.Cu" signal "L5")
		(12 "In5.Cu" signal "L6GND")
		(14 "In6.Cu" signal "L7VCC")
		(16 "In7.Cu" signal "L8VCC")
		(18 "In8.Cu" signal "L9GND")
		(20 "In9.Cu" signal "L10")
		(22 "In10.Cu" signal "L11GND")
		(24 "In11.Cu" signal "L12")
		(26 "In12.Cu" signal "L13GND")
		(2 "B.Cu" signal "BOTTOM")
		(9 "F.Adhes" user "F.Adhesive")
		(11 "B.Adhes" user "B.Adhesive")
		(13 "F.Paste" user "Package Geometry/Pastemask Top")
		(15 "B.Paste" user "Package Geometry/Pastemask Bottom")
		(5 "F.SilkS" user "Ref Des/Silkscreen Top")
		(7 "B.SilkS" user "Ref Des/Silkscreen Bottom")
		(1 "F.Mask" user "Board Geometry/Soldermask Top")
		(3 "B.Mask" user "Board Geometry/Soldermask Bottom")
		(17 "Dwgs.User" user "User.Drawings")
		(19 "Cmts.User" user "User.Comments")
		(21 "Eco1.User" user "User.Eco1")
		(23 "Eco2.User" user "User.Eco2")
		(25 "Edge.Cuts" user "Board Geometry/Outline")
		(27 "Margin" user)
		(31 "F.CrtYd" user "Package Geometry/Place Bound Top")
		(29 "B.CrtYd" user "Package Geometry/Place Bound Bottom")
		(35 "F.Fab" user "Ref Des/Assembly Top")
		(33 "B.Fab" user "Ref Des/Assembly Bottom")
	)
	(footprint ""
		(layer "F.Cu")
		(at 421.63619 -52.795932 -90)
		(property "Reference" "Q8E2"
			(at -1.98247 1.9685 0)
			(unlocked yes)
			(layer "F.SilkS")
			(effects
				(font
					(size 0.7874 0.5842)
					(thickness 0.1524)
				)
				(justify left)
			)
		)
		(property "Value" ""
			(at 0 0 270)
			(layer "F.Fab")
			(effects
				(font
					(size 1.27 1.27)
				)
			)
		)
		(duplicate_pad_numbers_are_jumpers no)
		(fp_line
			(start 0.9525 2.4765)
			(end 1.778 2.4765)
			(stroke
				(width 0.1524)
				(type default)
			)
			(layer "F.SilkS")
		)
		(fp_line
			(start 1.778 2.4765)
			(end 1.778 1.5875)
			(stroke
				(width 0.1524)
				(type default)
			)
			(layer "F.SilkS")
		)
		(fp_line
			(start 0.381 0.635)
			(end 0.381 1.27)
			(stroke
				(width 0.1524)
				(type default)
			)
			(layer "F.SilkS")
		)
		(fp_line
			(start 0.9525 -0.5715)
			(end 1.778 -0.5715)
			(stroke
				(width 0.1524)
				(type default)
			)
			(layer "F.SilkS")
		)
		(fp_line
			(start 1.778 -0.5715)
			(end 1.778 0.3175)
			(stroke
				(width 0.1524)
				(type default)
			)
			(layer "F.SilkS")
		)
		(fp_circle
			(center -0.636524 -0.863854)
			(end -0.636524 -0.990854)
			(stroke
				(width 0.254)
				(type default)
			)
			(fill no)
			(layer "F.SilkS")
		)
		(fp_poly
			(pts
				(xy 1.778 2.4765) (xy 0.381 2.4765) (xy 0.381 -0.5715) (xy 1.778 -0.5715)
			)
			(stroke
				(width 0)
				(type default)
			)
			(fill no)
			(layer "F.CrtYd")
		)
		(fp_line
			(start 0.381 2.4765)
			(end 1.778 2.4765)
			(stroke
				(width 0.1)
				(type default)
			)
			(layer "F.Fab")
		)
		(fp_line
			(start 1.778 2.4765)
			(end 1.778 -0.5715)
			(stroke
				(width 0.1)
				(type default)
			)
			(layer "F.Fab")
		)
		(fp_line
			(start 0.381 -0.5715)
			(end 0.381 2.4765)
			(stroke
				(width 0.1)
				(type default)
			)
			(layer "F.Fab")
		)
		(fp_line
			(start 1.778 -0.5715)
			(end 0.381 -0.5715)
			(stroke
				(width 0.1)
				(type default)
			)
			(layer "F.Fab")
		)
		(fp_circle
			(center -0.9525 -0.9271)
			(end -0.9525 -1.0541)
			(stroke
				(width 0.254)
				(type default)
			)
			(fill no)
			(layer "F.Fab")
		)
		(pad "1" smd rect
			(at 0 0 270)
			(size 1.143 0.508)
			(layers "F.Cu" "F.Mask" "F.Paste")
			(net "RST_RSMRST_DLY")
		)
		(pad "2" smd rect
			(at 0 1.905 270)
			(size 1.143 0.508)
			(layers "F.Cu" "F.Mask" "F.Paste")
			(net "GND")
		)
		(pad "3" smd rect
			(at 2.159 0.9525 270)
			(size 1.143 0.508)
			(layers "F.Cu" "F.Mask" "F.Paste")
			(net "IRQ_SML0_ALERT_N")
		)
	)
	(footprint ""
		(layer "F.Cu")
		(at 402.66874 -32.902652 -90)
		(property "Reference" "R2U33"
			(at 0 0 270)
			(layer "F.SilkS")
			(hide yes)
			(effects
				(font
					(size 1.27 1.27)
				)
			)
		)
		(property "Value" ""
			(at 0 0 270)
			(layer "F.Fab")
			(effects
				(font
					(size 1.27 1.27)
				)
			)
		)
		(duplicate_pad_numbers_are_jumpers no)
		(fp_poly
			(pts
				(xy -0.2794 -0.1016) (xy 0.2794 -0.1016) (xy 0.2794 0.9906) (xy -0.2794 0.9906)
			)
			(stroke
				(width 0)
				(type default)
			)
			(fill no)
			(layer "F.CrtYd")
		)
		(fp_line
			(start -0.2794 0.9906)
			(end 0.2794 0.9906)
			(stroke
				(width 0.1)
				(type default)
			)
			(layer "F.Fab")
		)
		(fp_line
			(start 0.2794 0.9906)
			(end 0.2794 -0.1016)
			(stroke
				(width 0.1)
				(type default)
			)
			(layer "F.Fab")
		)
		(fp_line
			(start -0.2794 -0.1016)
			(end -0.2794 0.9906)
			(stroke
				(width 0.1)
				(type default)
			)
			(layer "F.Fab")
		)
		(fp_line
			(start 0.2794 -0.1016)
			(end -0.2794 -0.1016)
			(stroke
				(width 0.1)
				(type default)
			)
			(layer "F.Fab")
		)
		(pad "1" smd rect
			(at 0 0 270)
			(size 0.508 0.508)
			(layers "F.Cu" "F.Mask" "F.Paste")
			(net "SMB_HOST_STBY_LVC3_SDA_R")
		)
		(pad "2" smd rect
			(at 0 0.889 270)
			(size 0.508 0.508)
			(layers "F.Cu" "F.Mask" "F.Paste")
			(net "SMB_HOST_STBY_LVC3_SDA")
		)
		(zone
			(layer "F.Cu")
			(hatch none 0.5)
			(connect_pads
				(clearance 0)
			)
			(min_thickness 0.25)
			(keepout
				(tracks not_allowed)
				(vias allowed)
				(pads allowed)
				(copperpour not_allowed)
				(footprints allowed)
			)
			(placement
				(enabled no)
				(sheetname "")
			)
			(fill
				(thermal_gap 0.5)
				(thermal_bridge_width 0.5)
				(island_removal_mode 0)
			)
			(polygon
				(pts
					(xy 402.03374 -33.156652) (xy 402.03374 -32.648652) (xy 402.41474 -32.648652) (xy 402.41474 -33.156652)
				)
			)
		)
		(zone
			(layer "F.Cu")
			(hatch none 0.5)
			(connect_pads
				(clearance 0)
			)
			(min_thickness 0.25)
			(keepout
				(tracks allowed)
				(vias not_allowed)
				(pads allowed)
				(copperpour not_allowed)
				(footprints allowed)
			)
			(placement
				(enabled no)
				(sheetname "")
			)
			(fill
				(thermal_gap 0.5)
				(thermal_bridge_width 0.5)
				(island_removal_mode 0)
			)
			(polygon
				(pts
					(xy 402.41474 -33.156652) (xy 402.41474 -32.648652) (xy 402.03374 -32.648652) (xy 402.03374 -33.156652)
				)
			)
		)
	)
	(footprint ""
		(layer "F.Cu")
		(at 432.51882 -129.2987 180)
		(property "Reference" "C8B5"
			(at 0 0 180)
			(layer "F.SilkS")
			(hide yes)
			(effects
				(font
					(size 1.27 1.27)
				)
			)
		)
		(property "Value" ""
			(at 0 0 180)
			(layer "F.Fab")
			(effects
				(font
					(size 1.27 1.27)
				)
			)
		)
		(duplicate_pad_numbers_are_jumpers no)
		(fp_poly
			(pts
				(xy 0.3048 -0.1016) (xy 0.3048 0.9906) (xy -0.3048 0.9906) (xy -0.3048 -0.1016)
			)
			(stroke
				(width 0)
				(type default)
			)
			(fill no)
			(layer "F.CrtYd")
		)
		(fp_line
			(start 0.3048 0.9906)
			(end 0.3048 -0.1016)
			(stroke
				(width 0.1)
				(type default)
			)
			(layer "F.Fab")
		)
		(fp_line
			(start 0.3048 -0.1016)
			(end -0.3048 -0.1016)
			(stroke
				(width 0.1)
				(type default)
			)
			(layer "F.Fab")
		)
		(fp_line
			(start -0.3048 0.9906)
			(end 0.3048 0.9906)
			(stroke
				(width 0.1)
				(type default)
			)
			(layer "F.Fab")
		)
		(fp_line
			(start -0.3048 -0.1016)
			(end -0.3048 0.9906)
			(stroke
				(width 0.1)
				(type default)
			)
			(layer "F.Fab")
		)
		(pad "1" smd rect
			(at 0 0 180)
			(size 0.508 0.508)
			(layers "F.Cu" "F.Mask" "F.Paste")
			(net "P5V_STBY")
		)
		(pad "2" smd rect
			(at 0 0.889 180)
			(size 0.508 0.508)
			(layers "F.Cu" "F.Mask" "F.Paste")
			(net "GND")
		)
		(zone
			(layer "F.Cu")
			(hatch none 0.5)
			(connect_pads
				(clearance 0)
			)
			(min_thickness 0.25)
			(keepout
				(tracks not_allowed)
				(vias allowed)
				(pads allowed)
				(copperpour not_allowed)
				(footprints allowed)
			)
			(placement
				(enabled no)
				(sheetname "")
			)
			(fill
				(thermal_gap 0.5)
				(thermal_bridge_width 0.5)
				(island_removal_mode 0)
			)
			(polygon
				(pts
					(xy 432.77282 -129.9337) (xy 432.26482 -129.9337) (xy 432.26482 -129.5527) (xy 432.77282 -129.5527)
				)
			)
		)
		(zone
			(layer "F.Cu")
			(hatch none 0.5)
			(connect_pads
				(clearance 0)
			)
			(min_thickness 0.25)
			(keepout
				(tracks allowed)
				(vias not_allowed)
				(pads allowed)
				(copperpour not_allowed)
				(footprints allowed)
			)
			(placement
				(enabled no)
				(sheetname "")
			)
			(fill
				(thermal_gap 0.5)
				(thermal_bridge_width 0.5)
				(island_removal_mode 0)
			)
			(polygon
				(pts
					(xy 432.77282 -129.5527) (xy 432.26482 -129.5527) (xy 432.26482 -129.9337) (xy 432.77282 -129.9337)
				)
			)
		)
	)
)
